# T6G (Grand Teton) — schematic netlist excerpt (pin names and nets, part order shuffled) for the footprints in the layout excerpt that follows; sources: Cadence DE-HDL packaged netlist, KiCad conversion of 04192023_DAF0TMB3IC0_F0TG_MB_C_brd_V02_OCP.brd

PC8008  Q_CAP  1UF 16V 10% X7R  pkg 0603  page 190 : A = P12V_AUX ; B = GND
R258  Q_RES  0 5% CHIP  pkg 0402LF  page 81 : A = FM_CPU0_HDT_CONN_TESTEN ; B = CPU0_HDT_CONN_TESTEN

(kicad_pcb
	(version 20260206)
	(generator "pcbnew")
	(generator_version "10.0")
	(general
		(thickness 1.6)
		(legacy_teardrops no)
	)
	(paper "A4")
	(title_block
		(title "04192023_DAF0TMB3IC0_F0TG_MB_C_brd_V02_OCP.brd")
		(comment 1 "Grand Teton / footprints 2366-2367 of 8354")
	)
	(layers
		(0 "F.Cu" signal "TOP")
		(4 "In1.Cu" signal "GND")
		(6 "In2.Cu" signal "IN1")
		(8 "In3.Cu" signal "GND1")
		(10 "In4.Cu" signal "IN2")
		(12 "In5.Cu" signal "GND2")
		(14 "In6.Cu" signal "IN3")
		(16 "In7.Cu" signal "GND3")
		(18 "In8.Cu" signal "VCC")
		(20 "In9.Cu" signal "VCC1")
		(22 "In10.Cu" signal "GND4")
		(24 "In11.Cu" signal "IN4")
		(26 "In12.Cu" signal "GND5")
		(28 "In13.Cu" signal "IN5")
		(30 "In14.Cu" signal "GND6")
		(32 "In15.Cu" signal "IN6")
		(34 "In16.Cu" signal "GND7")
		(2 "B.Cu" signal "BOTTOM")
		(9 "F.Adhes" user "F.Adhesive")
		(11 "B.Adhes" user "B.Adhesive")
		(13 "F.Paste" user "Package Geometry/Pastemask Top")
		(15 "B.Paste" user "Package Geometry/Pastemask Bottom")
		(5 "F.SilkS" user "Ref Des/Silkscreen Top")
		(7 "B.SilkS" user "Ref Des/Silkscreen Bottom")
		(1 "F.Mask" user "Board Geometry/Soldermask Top")
		(3 "B.Mask" user "Board Geometry/Soldermask Bottom")
		(17 "Dwgs.User" user "User.Drawings")
		(19 "Cmts.User" user "User.Comments")
		(21 "Eco1.User" user "User.Eco1")
		(23 "Eco2.User" user "User.Eco2")
		(25 "Edge.Cuts" user "Board Geometry/Outline")
		(27 "Margin" user)
		(31 "F.CrtYd" user "Package Geometry/Place Bound Top")
		(29 "B.CrtYd" user "Package Geometry/Place Bound Bottom")
		(35 "F.Fab" user "Ref Des/Assembly Top")
		(33 "B.Fab" user "Ref Des/Assembly Bottom")
	)
	(footprint ""
		(layer "F.Cu")
		(at 189.103 -129.377948 90)
		(property "Reference" "R258"
			(at 0 0 90)
			(layer "F.SilkS")
			(hide yes)
			(effects
				(font
					(size 1.27 1.27)
				)
			)
		)
		(property "Value" ""
			(at 0 0 90)
			(layer "F.Fab")
			(effects
				(font
					(size 1.27 1.27)
				)
			)
		)
		(duplicate_pad_numbers_are_jumpers no)
		(fp_line
			(start 0.7874 -0.4064)
			(end 0.7874 0.4064)
			(stroke
				(width 0.1524)
				(type default)
			)
			(layer "F.SilkS")
		)
		(fp_line
			(start -0.7874 -0.4064)
			(end 0.7874 -0.4064)
			(stroke
				(width 0.1524)
				(type default)
			)
			(layer "F.SilkS")
		)
		(fp_line
			(start 0.7874 0.4064)
			(end -0.7874 0.4064)
			(stroke
				(width 0.1524)
				(type default)
			)
			(layer "F.SilkS")
		)
		(fp_line
			(start -0.7874 0.4064)
			(end -0.7874 -0.4064)
			(stroke
				(width 0.1524)
				(type default)
			)
			(layer "F.SilkS")
		)
		(fp_line
			(start -0.12065 -0.305054)
			(end -0.12065 -0.2794)
			(stroke
				(width 0.1)
				(type default)
			)
			(layer "F.Fab")
		)
		(fp_line
			(start -0.67945 -0.305054)
			(end -0.12065 -0.305054)
			(stroke
				(width 0.1)
				(type default)
			)
			(layer "F.Fab")
		)
		(fp_line
			(start 0.67945 -0.3048)
			(end 0.67945 0.3048)
			(stroke
				(width 0.1)
				(type default)
			)
			(layer "F.Fab")
		)
		(fp_line
			(start 0.12065 -0.3048)
			(end 0.67945 -0.3048)
			(stroke
				(width 0.1)
				(type default)
			)
			(layer "F.Fab")
		)
		(fp_line
			(start 0.12065 -0.2794)
			(end 0.12065 -0.3048)
			(stroke
				(width 0.1)
				(type default)
			)
			(layer "F.Fab")
		)
		(fp_line
			(start -0.12065 -0.2794)
			(end 0.12065 -0.2794)
			(stroke
				(width 0.1)
				(type default)
			)
			(layer "F.Fab")
		)
		(fp_line
			(start 0.120396 0.2794)
			(end -0.12065 0.2794)
			(stroke
				(width 0.1)
				(type default)
			)
			(layer "F.Fab")
		)
		(fp_line
			(start -0.12065 0.2794)
			(end -0.12065 0.3048)
			(stroke
				(width 0.1)
				(type default)
			)
			(layer "F.Fab")
		)
		(fp_line
			(start 0.67945 0.3048)
			(end 0.120396 0.3048)
			(stroke
				(width 0.1)
				(type default)
			)
			(layer "F.Fab")
		)
		(fp_line
			(start 0.120396 0.3048)
			(end 0.120396 0.2794)
			(stroke
				(width 0.1)
				(type default)
			)
			(layer "F.Fab")
		)
		(fp_line
			(start -0.12065 0.3048)
			(end -0.67945 0.3048)
			(stroke
				(width 0.1)
				(type default)
			)
			(layer "F.Fab")
		)
		(fp_line
			(start -0.67945 0.3048)
			(end -0.67945 -0.305054)
			(stroke
				(width 0.1)
				(type default)
			)
			(layer "F.Fab")
		)
		(pad "1" smd circle
			(at -0.40005 0 90)
			(size 0 0)
			(layers "F.Cu" "F.Mask" "F.Paste")
			(net "FM_CPU0_HDT_CONN_TESTEN")
		)
		(pad "2" smd circle
			(at 0.40005 0 90)
			(size 0 0)
			(layers "F.Cu" "F.Mask" "F.Paste")
			(net "CPU0_HDT_CONN_TESTEN")
		)
	)
	(footprint ""
		(layer "F.Cu")
		(at 460.292196 -47.929546 -90)
		(property "Reference" "PC8008"
			(at 0 0 270)
			(layer "F.SilkS")
			(hide yes)
			(effects
				(font
					(size 1.27 1.27)
				)
			)
		)
		(property "Value" ""
			(at 0 0 270)
			(layer "F.Fab")
			(effects
				(font
					(size 1.27 1.27)
				)
			)
		)
		(duplicate_pad_numbers_are_jumpers no)
		(fp_line
			(start -1.2954 0.5842)
			(end -1.2954 -0.5842)
			(stroke
				(width 0.1524)
				(type default)
			)
			(layer "F.SilkS")
		)
		(fp_line
			(start 1.2954 0.5842)
			(end -1.2954 0.5842)
			(stroke
				(width 0.1524)
				(type default)
			)
			(layer "F.SilkS")
		)
		(fp_line
			(start -1.2954 -0.5842)
			(end 1.2954 -0.5842)
			(stroke
				(width 0.1524)
				(type default)
			)
			(layer "F.SilkS")
		)
		(fp_line
			(start 1.2954 -0.5842)
			(end 1.2954 0.5842)
			(stroke
				(width 0.1524)
				(type default)
			)
			(layer "F.SilkS")
		)
		(fp_line
			(start -0.8636 0.4572)
			(end -0.8636 0.4064)
			(stroke
				(width 0.1)
				(type default)
			)
			(layer "F.Fab")
		)
		(fp_line
			(start 0.8636 0.4572)
			(end -0.8636 0.4572)
			(stroke
				(width 0.1)
				(type default)
			)
			(layer "F.Fab")
		)
		(fp_line
			(start -1.1938 0.4064)
			(end -1.1938 -0.4064)
			(stroke
				(width 0.1)
				(type default)
			)
			(layer "F.Fab")
		)
		(fp_line
			(start -0.8636 0.4064)
			(end -1.1938 0.4064)
			(stroke
				(width 0.1)
				(type default)
			)
			(layer "F.Fab")
		)
		(fp_line
			(start 0.8636 0.4064)
			(end 0.8636 0.4572)
			(stroke
				(width 0.1)
				(type default)
			)
			(layer "F.Fab")
		)
		(fp_line
			(start 1.1938 0.4064)
			(end 0.8636 0.4064)
			(stroke
				(width 0.1)
				(type default)
			)
			(layer "F.Fab")
		)
		(fp_line
			(start -1.1938 -0.4064)
			(end -0.8636 -0.4064)
			(stroke
				(width 0.1)
				(type default)
			)
			(layer "F.Fab")
		)
		(fp_line
			(start -0.8636 -0.4064)
			(end -0.8636 -0.4572)
			(stroke
				(width 0.1)
				(type default)
			)
			(layer "F.Fab")
		)
		(fp_line
			(start 0.8636 -0.4064)
			(end 1.1938 -0.4064)
			(stroke
				(width 0.1)
				(type default)
			)
			(layer "F.Fab")
		)
		(fp_line
			(start 1.1938 -0.4064)
			(end 1.1938 0.4064)
			(stroke
				(width 0.1)
				(type default)
			)
			(layer "F.Fab")
		)
		(fp_line
			(start -0.8636 -0.4572)
			(end 0.8636 -0.4572)
			(stroke
				(width 0.1)
				(type default)
			)
			(layer "F.Fab")
		)
		(fp_line
			(start 0.8636 -0.4572)
			(end 0.8636 -0.4064)
			(stroke
				(width 0.1)
				(type default)
			)
			(layer "F.Fab")
		)
		(pad "1" smd rect
			(at -0.7366 0 180)
			(size 0.7112 0.8128)
			(layers "F.Cu" "F.Mask" "F.Paste")
			(net "P12V_AUX")
		)
		(pad "2" smd rect
			(at 0.7366 0 180)
			(size 0.7112 0.8128)
			(layers "F.Cu" "F.Mask" "F.Paste")
			(net "GND")
		)
	)
)
